# S9S_MB_2U (Grand Teton) — schematic netlist excerpt (pin names and nets, part order shuffled) for the footprints in the layout excerpt that follows; sources: Cadence DE-HDL packaged netlist, KiCad conversion of 03242023_DA0F0TMBIJ0_F0T_Motherboard_J_brd_V01_OCP.brd

R4088  Q_RES  0 5% CHIP  pkg 0402LF  page 214 : A = FM_JTAG_BMC_MUX_SEL_FROM_BMC_R ; B = FM_JTAG_BMC_MUX_SEL
R4106  Q_RES  10K 1% CHIP  pkg 0402LF  page 184 : A = PD_GPP_M_8 ; B = GND

(kicad_pcb
	(version 20260206)
	(generator "pcbnew")
	(generator_version "10.0")
	(general
		(thickness 1.6)
		(legacy_teardrops no)
	)
	(paper "A4")
	(title_block
		(title "03242023_DA0F0TMBIJ0_F0T_Motherboard_J_brd_V01_OCP.brd")
		(comment 1 "Grand Teton / footprints 4335-4336 of 6105")
	)
	(layers
		(0 "F.Cu" signal "TOP")
		(4 "In1.Cu" signal "GND")
		(6 "In2.Cu" signal "IN1")
		(8 "In3.Cu" signal "GND1")
		(10 "In4.Cu" signal "IN2")
		(12 "In5.Cu" signal "GND2")
		(14 "In6.Cu" signal "IN3")
		(16 "In7.Cu" signal "GND3")
		(18 "In8.Cu" signal "VCC")
		(20 "In9.Cu" signal "VCC1")
		(22 "In10.Cu" signal "GND4")
		(24 "In11.Cu" signal "IN4")
		(26 "In12.Cu" signal "GND5")
		(28 "In13.Cu" signal "IN5")
		(30 "In14.Cu" signal "GND6")
		(32 "In15.Cu" signal "IN6")
		(34 "In16.Cu" signal "GND7")
		(2 "B.Cu" signal "BOTTOM")
		(9 "F.Adhes" user "F.Adhesive")
		(11 "B.Adhes" user "B.Adhesive")
		(13 "F.Paste" user "Package Geometry/Pastemask Top")
		(15 "B.Paste" user "Package Geometry/Pastemask Bottom")
		(5 "F.SilkS" user "Ref Des/Silkscreen Top")
		(7 "B.SilkS" user "Ref Des/Silkscreen Bottom")
		(1 "F.Mask" user "Board Geometry/Soldermask Top")
		(3 "B.Mask" user "Board Geometry/Soldermask Bottom")
		(17 "Dwgs.User" user "User.Drawings")
		(19 "Cmts.User" user "User.Comments")
		(21 "Eco1.User" user "User.Eco1")
		(23 "Eco2.User" user "User.Eco2")
		(25 "Edge.Cuts" user "Board Geometry/Outline")
		(27 "Margin" user)
		(31 "F.CrtYd" user "Package Geometry/Place Bound Top")
		(29 "B.CrtYd" user "Package Geometry/Place Bound Bottom")
		(35 "F.Fab" user "Ref Des/Assembly Top")
		(33 "B.Fab" user "Ref Des/Assembly Bottom")
	)
	(footprint ""
		(layer "B.Cu")
		(at 311.84088 -53.304948)
		(property "Reference" "R4106"
			(at 0 0 0)
			(layer "B.SilkS")
			(hide yes)
			(effects
				(font
					(size 1.27 1.27)
				)
				(justify mirror)
			)
		)
		(property "Value" ""
			(at 0 0 0)
			(layer "B.Fab")
			(effects
				(font
					(size 1.27 1.27)
				)
				(justify mirror)
			)
		)
		(duplicate_pad_numbers_are_jumpers no)
		(fp_line
			(start -0.7874 -0.4064)
			(end -0.7874 0.4064)
			(stroke
				(width 0.1524)
				(type default)
			)
			(layer "B.SilkS")
		)
		(fp_line
			(start -0.7874 0.4064)
			(end 0.7874 0.4064)
			(stroke
				(width 0.1524)
				(type default)
			)
			(layer "B.SilkS")
		)
		(fp_line
			(start 0.7874 -0.4064)
			(end -0.7874 -0.4064)
			(stroke
				(width 0.1524)
				(type default)
			)
			(layer "B.SilkS")
		)
		(fp_line
			(start 0.7874 0.4064)
			(end 0.7874 -0.4064)
			(stroke
				(width 0.1524)
				(type default)
			)
			(layer "B.SilkS")
		)
		(fp_line
			(start -0.67945 -0.3048)
			(end -0.67945 0.3048)
			(stroke
				(width 0.1)
				(type default)
			)
			(layer "B.Fab")
		)
		(fp_line
			(start -0.67945 0.3048)
			(end -0.120396 0.3048)
			(stroke
				(width 0.1)
				(type default)
			)
			(layer "B.Fab")
		)
		(fp_line
			(start -0.12065 -0.3048)
			(end -0.67945 -0.3048)
			(stroke
				(width 0.1)
				(type default)
			)
			(layer "B.Fab")
		)
		(fp_line
			(start -0.12065 -0.2794)
			(end -0.12065 -0.3048)
			(stroke
				(width 0.1)
				(type default)
			)
			(layer "B.Fab")
		)
		(fp_line
			(start -0.120396 0.2794)
			(end 0.12065 0.2794)
			(stroke
				(width 0.1)
				(type default)
			)
			(layer "B.Fab")
		)
		(fp_line
			(start -0.120396 0.3048)
			(end -0.120396 0.2794)
			(stroke
				(width 0.1)
				(type default)
			)
			(layer "B.Fab")
		)
		(fp_line
			(start 0.12065 -0.305054)
			(end 0.12065 -0.2794)
			(stroke
				(width 0.1)
				(type default)
			)
			(layer "B.Fab")
		)
		(fp_line
			(start 0.12065 -0.2794)
			(end -0.12065 -0.2794)
			(stroke
				(width 0.1)
				(type default)
			)
			(layer "B.Fab")
		)
		(fp_line
			(start 0.12065 0.2794)
			(end 0.12065 0.3048)
			(stroke
				(width 0.1)
				(type default)
			)
			(layer "B.Fab")
		)
		(fp_line
			(start 0.12065 0.3048)
			(end 0.67945 0.3048)
			(stroke
				(width 0.1)
				(type default)
			)
			(layer "B.Fab")
		)
		(fp_line
			(start 0.67945 -0.305054)
			(end 0.12065 -0.305054)
			(stroke
				(width 0.1)
				(type default)
			)
			(layer "B.Fab")
		)
		(fp_line
			(start 0.67945 0.3048)
			(end 0.67945 -0.305054)
			(stroke
				(width 0.1)
				(type default)
			)
			(layer "B.Fab")
		)
		(pad "1" smd circle
			(at 0.40005 0 180)
			(size 0 0)
			(layers "B.Cu" "B.Mask" "B.Paste")
			(net "PD_GPP_M_8")
		)
		(pad "2" smd circle
			(at -0.40005 0 180)
			(size 0 0)
			(layers "B.Cu" "B.Mask" "B.Paste")
			(net "GND")
		)
	)
	(footprint ""
		(layer "B.Cu")
		(at 147.70608 -13.782548 90)
		(property "Reference" "R4088"
			(at 0 0 90)
			(layer "B.SilkS")
			(hide yes)
			(effects
				(font
					(size 1.27 1.27)
				)
				(justify mirror)
			)
		)
		(property "Value" ""
			(at 0 0 90)
			(layer "B.Fab")
			(effects
				(font
					(size 1.27 1.27)
				)
				(justify mirror)
			)
		)
		(duplicate_pad_numbers_are_jumpers no)
		(fp_line
			(start 0.7874 -0.4064)
			(end -0.7874 -0.4064)
			(stroke
				(width 0.1524)
				(type default)
			)
			(layer "B.SilkS")
		)
		(fp_line
			(start -0.7874 -0.4064)
			(end -0.7874 0.4064)
			(stroke
				(width 0.1524)
				(type default)
			)
			(layer "B.SilkS")
		)
		(fp_line
			(start 0.7874 0.4064)
			(end 0.7874 -0.4064)
			(stroke
				(width 0.1524)
				(type default)
			)
			(layer "B.SilkS")
		)
		(fp_line
			(start -0.7874 0.4064)
			(end 0.7874 0.4064)
			(stroke
				(width 0.1524)
				(type default)
			)
			(layer "B.SilkS")
		)
		(fp_line
			(start 0.67945 -0.305054)
			(end 0.12065 -0.305054)
			(stroke
				(width 0.1)
				(type default)
			)
			(layer "B.Fab")
		)
		(fp_line
			(start 0.12065 -0.305054)
			(end 0.12065 -0.2794)
			(stroke
				(width 0.1)
				(type default)
			)
			(layer "B.Fab")
		)
		(fp_line
			(start -0.12065 -0.3048)
			(end -0.67945 -0.3048)
			(stroke
				(width 0.1)
				(type default)
			)
			(layer "B.Fab")
		)
		(fp_line
			(start -0.67945 -0.3048)
			(end -0.67945 0.3048)
			(stroke
				(width 0.1)
				(type default)
			)
			(layer "B.Fab")
		)
		(fp_line
			(start 0.12065 -0.2794)
			(end -0.12065 -0.2794)
			(stroke
				(width 0.1)
				(type default)
			)
			(layer "B.Fab")
		)
		(fp_line
			(start -0.12065 -0.2794)
			(end -0.12065 -0.3048)
			(stroke
				(width 0.1)
				(type default)
			)
			(layer "B.Fab")
		)
		(fp_line
			(start 0.12065 0.2794)
			(end 0.12065 0.3048)
			(stroke
				(width 0.1)
				(type default)
			)
			(layer "B.Fab")
		)
		(fp_line
			(start -0.120396 0.2794)
			(end 0.12065 0.2794)
			(stroke
				(width 0.1)
				(type default)
			)
			(layer "B.Fab")
		)
		(fp_line
			(start 0.67945 0.3048)
			(end 0.67945 -0.305054)
			(stroke
				(width 0.1)
				(type default)
			)
			(layer "B.Fab")
		)
		(fp_line
			(start 0.12065 0.3048)
			(end 0.67945 0.3048)
			(stroke
				(width 0.1)
				(type default)
			)
			(layer "B.Fab")
		)
		(fp_line
			(start -0.120396 0.3048)
			(end -0.120396 0.2794)
			(stroke
				(width 0.1)
				(type default)
			)
			(layer "B.Fab")
		)
		(fp_line
			(start -0.67945 0.3048)
			(end -0.120396 0.3048)
			(stroke
				(width 0.1)
				(type default)
			)
			(layer "B.Fab")
		)
		(pad "1" smd circle
			(at 0.40005 0 270)
			(size 0 0)
			(layers "B.Cu" "B.Mask" "B.Paste")
			(net "FM_JTAG_BMC_MUX_SEL_FROM_BMC_R")
		)
		(pad "2" smd circle
			(at -0.40005 0 270)
			(size 0 0)
			(layers "B.Cu" "B.Mask" "B.Paste")
			(net "FM_JTAG_BMC_MUX_SEL")
		)
	)
)
